# S9S_MB_2U (Grand Teton) — schematic netlist excerpt (pin names and nets, part order shuffled) for the footprints in the layout excerpt that follows; sources: Cadence DE-HDL packaged netlist, KiCad conversion of 03242023_DA0F0TMBIJ0_F0T_Motherboard_J_brd_V01_OCP.brd

PC2159  Q_CAP  1UF 25V 10% EMPTY  pkg C0402  page 157 : A = P3V3_AUX ; B = GND
R4281  Q_RES  1K 1% EMPTY  pkg 0402LF  page 169 : A = P3V3_AUX ; B = FM_USB3_1_EQB

(kicad_pcb
	(version 20260206)
	(generator "pcbnew")
	(generator_version "10.0")
	(general
		(thickness 1.6)
		(legacy_teardrops no)
	)
	(paper "A4")
	(title_block
		(title "03242023_DA0F0TMBIJ0_F0T_Motherboard_J_brd_V01_OCP.brd")
		(comment 1 "Grand Teton / footprints 2384-2385 of 6105")
	)
	(layers
		(0 "F.Cu" signal "TOP")
		(4 "In1.Cu" signal "GND")
		(6 "In2.Cu" signal "IN1")
		(8 "In3.Cu" signal "GND1")
		(10 "In4.Cu" signal "IN2")
		(12 "In5.Cu" signal "GND2")
		(14 "In6.Cu" signal "IN3")
		(16 "In7.Cu" signal "GND3")
		(18 "In8.Cu" signal "VCC")
		(20 "In9.Cu" signal "VCC1")
		(22 "In10.Cu" signal "GND4")
		(24 "In11.Cu" signal "IN4")
		(26 "In12.Cu" signal "GND5")
		(28 "In13.Cu" signal "IN5")
		(30 "In14.Cu" signal "GND6")
		(32 "In15.Cu" signal "IN6")
		(34 "In16.Cu" signal "GND7")
		(2 "B.Cu" signal "BOTTOM")
		(9 "F.Adhes" user "F.Adhesive")
		(11 "B.Adhes" user "B.Adhesive")
		(13 "F.Paste" user "Package Geometry/Pastemask Top")
		(15 "B.Paste" user "Package Geometry/Pastemask Bottom")
		(5 "F.SilkS" user "Ref Des/Silkscreen Top")
		(7 "B.SilkS" user "Ref Des/Silkscreen Bottom")
		(1 "F.Mask" user "Board Geometry/Soldermask Top")
		(3 "B.Mask" user "Board Geometry/Soldermask Bottom")
		(17 "Dwgs.User" user "User.Drawings")
		(19 "Cmts.User" user "User.Comments")
		(21 "Eco1.User" user "User.Eco1")
		(23 "Eco2.User" user "User.Eco2")
		(25 "Edge.Cuts" user "Board Geometry/Outline")
		(27 "Margin" user)
		(31 "F.CrtYd" user "Package Geometry/Place Bound Top")
		(29 "B.CrtYd" user "Package Geometry/Place Bound Bottom")
		(35 "F.Fab" user "Ref Des/Assembly Top")
		(33 "B.Fab" user "Ref Des/Assembly Bottom")
	)
	(footprint ""
		(layer "F.Cu")
		(at 418.11194 -105.207308 180)
		(property "Reference" "PC2159"
			(at 0 0 180)
			(layer "F.SilkS")
			(hide yes)
			(effects
				(font
					(size 1.27 1.27)
				)
			)
		)
		(property "Value" ""
			(at 0 0 180)
			(layer "F.Fab")
			(effects
				(font
					(size 1.27 1.27)
				)
			)
		)
		(duplicate_pad_numbers_are_jumpers no)
		(fp_line
			(start 0.7874 0.4064)
			(end -0.7874 0.4064)
			(stroke
				(width 0.1524)
				(type default)
			)
			(layer "F.SilkS")
		)
		(fp_line
			(start 0.7874 -0.4064)
			(end 0.7874 0.4064)
			(stroke
				(width 0.1524)
				(type default)
			)
			(layer "F.SilkS")
		)
		(fp_line
			(start -0.7874 0.4064)
			(end -0.7874 -0.4064)
			(stroke
				(width 0.1524)
				(type default)
			)
			(layer "F.SilkS")
		)
		(fp_line
			(start -0.7874 -0.4064)
			(end 0.7874 -0.4064)
			(stroke
				(width 0.1524)
				(type default)
			)
			(layer "F.SilkS")
		)
		(fp_line
			(start 0.67945 0.3048)
			(end 0.120396 0.3048)
			(stroke
				(width 0.1)
				(type default)
			)
			(layer "F.Fab")
		)
		(fp_line
			(start 0.67945 -0.3048)
			(end 0.67945 0.3048)
			(stroke
				(width 0.1)
				(type default)
			)
			(layer "F.Fab")
		)
		(fp_line
			(start 0.12065 -0.2794)
			(end 0.12065 -0.3048)
			(stroke
				(width 0.1)
				(type default)
			)
			(layer "F.Fab")
		)
		(fp_line
			(start 0.12065 -0.3048)
			(end 0.67945 -0.3048)
			(stroke
				(width 0.1)
				(type default)
			)
			(layer "F.Fab")
		)
		(fp_line
			(start 0.120396 0.3048)
			(end 0.120396 0.2794)
			(stroke
				(width 0.1)
				(type default)
			)
			(layer "F.Fab")
		)
		(fp_line
			(start 0.120396 0.2794)
			(end -0.12065 0.2794)
			(stroke
				(width 0.1)
				(type default)
			)
			(layer "F.Fab")
		)
		(fp_line
			(start -0.12065 0.3048)
			(end -0.67945 0.3048)
			(stroke
				(width 0.1)
				(type default)
			)
			(layer "F.Fab")
		)
		(fp_line
			(start -0.12065 0.2794)
			(end -0.12065 0.3048)
			(stroke
				(width 0.1)
				(type default)
			)
			(layer "F.Fab")
		)
		(fp_line
			(start -0.12065 -0.2794)
			(end 0.12065 -0.2794)
			(stroke
				(width 0.1)
				(type default)
			)
			(layer "F.Fab")
		)
		(fp_line
			(start -0.12065 -0.305054)
			(end -0.12065 -0.2794)
			(stroke
				(width 0.1)
				(type default)
			)
			(layer "F.Fab")
		)
		(fp_line
			(start -0.67945 0.3048)
			(end -0.67945 -0.305054)
			(stroke
				(width 0.1)
				(type default)
			)
			(layer "F.Fab")
		)
		(fp_line
			(start -0.67945 -0.305054)
			(end -0.12065 -0.305054)
			(stroke
				(width 0.1)
				(type default)
			)
			(layer "F.Fab")
		)
		(pad "1" smd circle
			(at -0.40005 0 180)
			(size 0 0)
			(layers "F.Cu" "F.Mask" "F.Paste")
			(net "P3V3_AUX")
		)
		(pad "2" smd circle
			(at 0.40005 0 180)
			(size 0 0)
			(layers "F.Cu" "F.Mask" "F.Paste")
			(net "GND")
		)
	)
	(footprint ""
		(layer "F.Cu")
		(at 136.6266 -28.578048 180)
		(property "Reference" "R4281"
			(at 0 0 180)
			(layer "F.SilkS")
			(hide yes)
			(effects
				(font
					(size 1.27 1.27)
				)
			)
		)
		(property "Value" ""
			(at 0 0 180)
			(layer "F.Fab")
			(effects
				(font
					(size 1.27 1.27)
				)
			)
		)
		(duplicate_pad_numbers_are_jumpers no)
		(fp_line
			(start 0.7874 0.4064)
			(end -0.7874 0.4064)
			(stroke
				(width 0.1524)
				(type default)
			)
			(layer "F.SilkS")
		)
		(fp_line
			(start 0.7874 -0.4064)
			(end 0.7874 0.4064)
			(stroke
				(width 0.1524)
				(type default)
			)
			(layer "F.SilkS")
		)
		(fp_line
			(start -0.7874 0.4064)
			(end -0.7874 -0.4064)
			(stroke
				(width 0.1524)
				(type default)
			)
			(layer "F.SilkS")
		)
		(fp_line
			(start -0.7874 -0.4064)
			(end 0.7874 -0.4064)
			(stroke
				(width 0.1524)
				(type default)
			)
			(layer "F.SilkS")
		)
		(fp_line
			(start 0.67945 0.3048)
			(end 0.120396 0.3048)
			(stroke
				(width 0.1)
				(type default)
			)
			(layer "F.Fab")
		)
		(fp_line
			(start 0.67945 -0.3048)
			(end 0.67945 0.3048)
			(stroke
				(width 0.1)
				(type default)
			)
			(layer "F.Fab")
		)
		(fp_line
			(start 0.12065 -0.2794)
			(end 0.12065 -0.3048)
			(stroke
				(width 0.1)
				(type default)
			)
			(layer "F.Fab")
		)
		(fp_line
			(start 0.12065 -0.3048)
			(end 0.67945 -0.3048)
			(stroke
				(width 0.1)
				(type default)
			)
			(layer "F.Fab")
		)
		(fp_line
			(start 0.120396 0.3048)
			(end 0.120396 0.2794)
			(stroke
				(width 0.1)
				(type default)
			)
			(layer "F.Fab")
		)
		(fp_line
			(start 0.120396 0.2794)
			(end -0.12065 0.2794)
			(stroke
				(width 0.1)
				(type default)
			)
			(layer "F.Fab")
		)
		(fp_line
			(start -0.12065 0.3048)
			(end -0.67945 0.3048)
			(stroke
				(width 0.1)
				(type default)
			)
			(layer "F.Fab")
		)
		(fp_line
			(start -0.12065 0.2794)
			(end -0.12065 0.3048)
			(stroke
				(width 0.1)
				(type default)
			)
			(layer "F.Fab")
		)
		(fp_line
			(start -0.12065 -0.2794)
			(end 0.12065 -0.2794)
			(stroke
				(width 0.1)
				(type default)
			)
			(layer "F.Fab")
		)
		(fp_line
			(start -0.12065 -0.305054)
			(end -0.12065 -0.2794)
			(stroke
				(width 0.1)
				(type default)
			)
			(layer "F.Fab")
		)
		(fp_line
			(start -0.67945 0.3048)
			(end -0.67945 -0.305054)
			(stroke
				(width 0.1)
				(type default)
			)
			(layer "F.Fab")
		)
		(fp_line
			(start -0.67945 -0.305054)
			(end -0.12065 -0.305054)
			(stroke
				(width 0.1)
				(type default)
			)
			(layer "F.Fab")
		)
		(pad "1" smd circle
			(at -0.40005 0 180)
			(size 0 0)
			(layers "F.Cu" "F.Mask" "F.Paste")
			(net "P3V3_AUX")
		)
		(pad "2" smd circle
			(at 0.40005 0 180)
			(size 0 0)
			(layers "F.Cu" "F.Mask" "F.Paste")
			(net "FM_USB3_1_EQB")
		)
	)
)
